(kicad_pcb
	(version 20260206)
	(generator "pcbnew")
	(generator_version "10.0")
	(general
		(thickness 1.6)
		(legacy_teardrops no)
	)
	(paper "A4")
	(title_block
		(title "9052_F0T_PDB_Converter_Brick_F_V03_1208_1600_OCP.brd")
		(comment 1 "Grand Teton / footprints 388-393 of 578")
	)
	(layers
		(0 "F.Cu" signal "TOP")
		(4 "In1.Cu" signal "GND")
		(6 "In2.Cu" signal "IN1")
		(8 "In3.Cu" signal "GND1")
		(10 "In4.Cu" signal "VCC")
		(12 "In5.Cu" signal "VCC1")
		(14 "In6.Cu" signal "GND2")
		(16 "In7.Cu" signal "IN2")
		(18 "In8.Cu" signal "GND3")
		(2 "B.Cu" signal "BOTTOM")
		(9 "F.Adhes" user "F.Adhesive")
		(11 "B.Adhes" user "B.Adhesive")
		(13 "F.Paste" user "Package Geometry/Pastemask Top")
		(15 "B.Paste" user "Package Geometry/Pastemask Bottom")
		(5 "F.SilkS" user "Ref Des/Silkscreen Top")
		(7 "B.SilkS" user "Ref Des/Silkscreen Bottom")
		(1 "F.Mask" user "Board Geometry/Soldermask Top")
		(3 "B.Mask" user "Board Geometry/Soldermask Bottom")
		(17 "Dwgs.User" user "User.Drawings")
		(19 "Cmts.User" user "User.Comments")
		(21 "Eco1.User" user "User.Eco1")
		(23 "Eco2.User" user "User.Eco2")
		(25 "Edge.Cuts" user "Board Geometry/Outline")
		(27 "Margin" user)
		(31 "F.CrtYd" user "Package Geometry/Place Bound Top")
		(29 "B.CrtYd" user "Package Geometry/Place Bound Bottom")
		(35 "F.Fab" user "Ref Des/Assembly Top")
		(33 "B.Fab" user "Ref Des/Assembly Bottom")
	)
	(footprint ""
		(layer "B.Cu")
		(at 292.227 -44.958)
		(property "Reference" "R5910"
			(at 0 0 0)
			(layer "B.SilkS")
			(hide yes)
			(effects
				(font
					(size 1.27 1.27)
				)
				(justify mirror)
			)
		)
		(property "Value" ""
			(at 0 0 0)
			(layer "B.Fab")
			(effects
				(font
					(size 1.27 1.27)
				)
				(justify mirror)
			)
		)
		(duplicate_pad_numbers_are_jumpers no)
		(fp_line
			(start -1.651 -0.8382)
			(end -1.651 0.8382)
			(stroke
				(width 0.1524)
				(type default)
			)
			(layer "B.SilkS")
		)
		(fp_line
			(start -1.651 0.8382)
			(end 1.651 0.8382)
			(stroke
				(width 0.1524)
				(type default)
			)
			(layer "B.SilkS")
		)
		(fp_line
			(start 1.651 -0.8382)
			(end -1.651 -0.8382)
			(stroke
				(width 0.1524)
				(type default)
			)
			(layer "B.SilkS")
		)
		(fp_line
			(start 1.651 0.8382)
			(end 1.651 -0.8382)
			(stroke
				(width 0.1524)
				(type default)
			)
			(layer "B.SilkS")
		)
		(fp_line
			(start -1.560576 -0.7366)
			(end -1.524 -0.7366)
			(stroke
				(width 0.1)
				(type default)
			)
			(layer "B.Fab")
		)
		(fp_line
			(start -1.560576 0.7366)
			(end -1.560576 -0.7366)
			(stroke
				(width 0.1)
				(type default)
			)
			(layer "B.Fab")
		)
		(fp_line
			(start -1.524 -0.7366)
			(end 1.524 -0.7366)
			(stroke
				(width 0.1)
				(type default)
			)
			(layer "B.Fab")
		)
		(fp_line
			(start -1.524 0.7366)
			(end -1.560576 0.7366)
			(stroke
				(width 0.1)
				(type default)
			)
			(layer "B.Fab")
		)
		(fp_line
			(start 1.524 -0.7366)
			(end 1.559814 -0.7366)
			(stroke
				(width 0.1)
				(type default)
			)
			(layer "B.Fab")
		)
		(fp_line
			(start 1.524 0.7366)
			(end -1.524 0.7366)
			(stroke
				(width 0.1)
				(type default)
			)
			(layer "B.Fab")
		)
		(fp_line
			(start 1.559814 -0.7366)
			(end 1.559814 0.7366)
			(stroke
				(width 0.1)
				(type default)
			)
			(layer "B.Fab")
		)
		(fp_line
			(start 1.559814 0.7366)
			(end 1.524 0.7366)
			(stroke
				(width 0.1)
				(type default)
			)
			(layer "B.Fab")
		)
		(pad "1" smd rect
			(at 0.94996 0)
			(size 1.1176 1.3716)
			(layers "B.Cu" "B.Mask" "B.Paste")
			(net "P52V_1_R")
		)
		(pad "2" smd rect
			(at -0.94996 0)
			(size 1.1176 1.3716)
			(layers "B.Cu" "B.Mask" "B.Paste")
			(net "FM_AC_PWR_CYCLE_N")
		)
	)
	(footprint ""
		(layer "B.Cu")
		(at 209.804 -69.723 -90)
		(property "Reference" "R18"
			(at 0 0 90)
			(layer "B.SilkS")
			(hide yes)
			(effects
				(font
					(size 1.27 1.27)
				)
				(justify mirror)
			)
		)
		(property "Value" ""
			(at 0 0 90)
			(layer "B.Fab")
			(effects
				(font
					(size 1.27 1.27)
				)
				(justify mirror)
			)
		)
		(duplicate_pad_numbers_are_jumpers no)
		(fp_line
			(start -0.7874 0.4064)
			(end 0.7874 0.4064)
			(stroke
				(width 0.1524)
				(type default)
			)
			(layer "B.SilkS")
		)
		(fp_line
			(start 0.7874 0.4064)
			(end 0.7874 -0.4064)
			(stroke
				(width 0.1524)
				(type default)
			)
			(layer "B.SilkS")
		)
		(fp_line
			(start -0.7874 -0.4064)
			(end -0.7874 0.4064)
			(stroke
				(width 0.1524)
				(type default)
			)
			(layer "B.SilkS")
		)
		(fp_line
			(start 0.7874 -0.4064)
			(end -0.7874 -0.4064)
			(stroke
				(width 0.1524)
				(type default)
			)
			(layer "B.SilkS")
		)
		(fp_line
			(start -0.67945 0.3048)
			(end -0.120396 0.3048)
			(stroke
				(width 0.1)
				(type default)
			)
			(layer "B.Fab")
		)
		(fp_line
			(start -0.120396 0.3048)
			(end -0.120396 0.2794)
			(stroke
				(width 0.1)
				(type default)
			)
			(layer "B.Fab")
		)
		(fp_line
			(start 0.12065 0.3048)
			(end 0.67945 0.3048)
			(stroke
				(width 0.1)
				(type default)
			)
			(layer "B.Fab")
		)
		(fp_line
			(start 0.67945 0.3048)
			(end 0.67945 -0.305054)
			(stroke
				(width 0.1)
				(type default)
			)
			(layer "B.Fab")
		)
		(fp_line
			(start -0.120396 0.2794)
			(end 0.12065 0.2794)
			(stroke
				(width 0.1)
				(type default)
			)
			(layer "B.Fab")
		)
		(fp_line
			(start 0.12065 0.2794)
			(end 0.12065 0.3048)
			(stroke
				(width 0.1)
				(type default)
			)
			(layer "B.Fab")
		)
		(fp_line
			(start -0.12065 -0.2794)
			(end -0.12065 -0.3048)
			(stroke
				(width 0.1)
				(type default)
			)
			(layer "B.Fab")
		)
		(fp_line
			(start 0.12065 -0.2794)
			(end -0.12065 -0.2794)
			(stroke
				(width 0.1)
				(type default)
			)
			(layer "B.Fab")
		)
		(fp_line
			(start -0.67945 -0.3048)
			(end -0.67945 0.3048)
			(stroke
				(width 0.1)
				(type default)
			)
			(layer "B.Fab")
		)
		(fp_line
			(start -0.12065 -0.3048)
			(end -0.67945 -0.3048)
			(stroke
				(width 0.1)
				(type default)
			)
			(layer "B.Fab")
		)
		(fp_line
			(start 0.12065 -0.305054)
			(end 0.12065 -0.2794)
			(stroke
				(width 0.1)
				(type default)
			)
			(layer "B.Fab")
		)
		(fp_line
			(start 0.67945 -0.305054)
			(end 0.12065 -0.305054)
			(stroke
				(width 0.1)
				(type default)
			)
			(layer "B.Fab")
		)
		(pad "1" smd circle
			(at 0.40005 0 90)
			(size 0 0)
			(layers "B.Cu" "B.Mask" "B.Paste")
			(net "P3V3_AUX")
		)
		(pad "2" smd circle
			(at -0.40005 0 90)
			(size 0 0)
			(layers "B.Cu" "B.Mask" "B.Paste")
			(net "PCA9555_A0")
		)
	)
	(footprint ""
		(layer "B.Cu")
		(at 136.779 -78.867)
		(property "Reference" "R162"
			(at 0 0 0)
			(layer "B.SilkS")
			(hide yes)
			(effects
				(font
					(size 1.27 1.27)
				)
				(justify mirror)
			)
		)
		(property "Value" ""
			(at 0 0 0)
			(layer "B.Fab")
			(effects
				(font
					(size 1.27 1.27)
				)
				(justify mirror)
			)
		)
		(duplicate_pad_numbers_are_jumpers no)
		(fp_line
			(start -0.7874 -0.4064)
			(end -0.7874 0.4064)
			(stroke
				(width 0.1524)
				(type default)
			)
			(layer "B.SilkS")
		)
		(fp_line
			(start -0.7874 0.4064)
			(end 0.7874 0.4064)
			(stroke
				(width 0.1524)
				(type default)
			)
			(layer "B.SilkS")
		)
		(fp_line
			(start 0.7874 -0.4064)
			(end -0.7874 -0.4064)
			(stroke
				(width 0.1524)
				(type default)
			)
			(layer "B.SilkS")
		)
		(fp_line
			(start 0.7874 0.4064)
			(end 0.7874 -0.4064)
			(stroke
				(width 0.1524)
				(type default)
			)
			(layer "B.SilkS")
		)
		(fp_line
			(start -0.67945 -0.3048)
			(end -0.67945 0.3048)
			(stroke
				(width 0.1)
				(type default)
			)
			(layer "B.Fab")
		)
		(fp_line
			(start -0.67945 0.3048)
			(end -0.120396 0.3048)
			(stroke
				(width 0.1)
				(type default)
			)
			(layer "B.Fab")
		)
		(fp_line
			(start -0.12065 -0.3048)
			(end -0.67945 -0.3048)
			(stroke
				(width 0.1)
				(type default)
			)
			(layer "B.Fab")
		)
		(fp_line
			(start -0.12065 -0.2794)
			(end -0.12065 -0.3048)
			(stroke
				(width 0.1)
				(type default)
			)
			(layer "B.Fab")
		)
		(fp_line
			(start -0.120396 0.2794)
			(end 0.12065 0.2794)
			(stroke
				(width 0.1)
				(type default)
			)
			(layer "B.Fab")
		)
		(fp_line
			(start -0.120396 0.3048)
			(end -0.120396 0.2794)
			(stroke
				(width 0.1)
				(type default)
			)
			(layer "B.Fab")
		)
		(fp_line
			(start 0.12065 -0.305054)
			(end 0.12065 -0.2794)
			(stroke
				(width 0.1)
				(type default)
			)
			(layer "B.Fab")
		)
		(fp_line
			(start 0.12065 -0.2794)
			(end -0.12065 -0.2794)
			(stroke
				(width 0.1)
				(type default)
			)
			(layer "B.Fab")
		)
		(fp_line
			(start 0.12065 0.2794)
			(end 0.12065 0.3048)
			(stroke
				(width 0.1)
				(type default)
			)
			(layer "B.Fab")
		)
		(fp_line
			(start 0.12065 0.3048)
			(end 0.67945 0.3048)
			(stroke
				(width 0.1)
				(type default)
			)
			(layer "B.Fab")
		)
		(fp_line
			(start 0.67945 -0.305054)
			(end 0.12065 -0.305054)
			(stroke
				(width 0.1)
				(type default)
			)
			(layer "B.Fab")
		)
		(fp_line
			(start 0.67945 0.3048)
			(end 0.67945 -0.305054)
			(stroke
				(width 0.1)
				(type default)
			)
			(layer "B.Fab")
		)
		(pad "1" smd circle
			(at 0.40005 0 180)
			(size 0 0)
			(layers "B.Cu" "B.Mask" "B.Paste")
			(net "P3V3_AUX")
		)
		(pad "2" smd circle
			(at -0.40005 0 180)
			(size 0 0)
			(layers "B.Cu" "B.Mask" "B.Paste")
			(net "P12V_BRICK0_ALERT_N")
		)
	)
	(footprint ""
		(layer "B.Cu")
		(at 179.065174 -78.867)
		(property "Reference" "R194"
			(at 0 0 0)
			(layer "B.SilkS")
			(hide yes)
			(effects
				(font
					(size 1.27 1.27)
				)
				(justify mirror)
			)
		)
		(property "Value" ""
			(at 0 0 0)
			(layer "B.Fab")
			(effects
				(font
					(size 1.27 1.27)
				)
				(justify mirror)
			)
		)
		(duplicate_pad_numbers_are_jumpers no)
		(fp_line
			(start -0.7874 -0.4064)
			(end -0.7874 0.4064)
			(stroke
				(width 0.1524)
				(type default)
			)
			(layer "B.SilkS")
		)
		(fp_line
			(start -0.7874 0.4064)
			(end 0.7874 0.4064)
			(stroke
				(width 0.1524)
				(type default)
			)
			(layer "B.SilkS")
		)
		(fp_line
			(start 0.7874 -0.4064)
			(end -0.7874 -0.4064)
			(stroke
				(width 0.1524)
				(type default)
			)
			(layer "B.SilkS")
		)
		(fp_line
			(start 0.7874 0.4064)
			(end 0.7874 -0.4064)
			(stroke
				(width 0.1524)
				(type default)
			)
			(layer "B.SilkS")
		)
		(fp_line
			(start -0.67945 -0.3048)
			(end -0.67945 0.3048)
			(stroke
				(width 0.1)
				(type default)
			)
			(layer "B.Fab")
		)
		(fp_line
			(start -0.67945 0.3048)
			(end -0.120396 0.3048)
			(stroke
				(width 0.1)
				(type default)
			)
			(layer "B.Fab")
		)
		(fp_line
			(start -0.12065 -0.3048)
			(end -0.67945 -0.3048)
			(stroke
				(width 0.1)
				(type default)
			)
			(layer "B.Fab")
		)
		(fp_line
			(start -0.12065 -0.2794)
			(end -0.12065 -0.3048)
			(stroke
				(width 0.1)
				(type default)
			)
			(layer "B.Fab")
		)
		(fp_line
			(start -0.120396 0.2794)
			(end 0.12065 0.2794)
			(stroke
				(width 0.1)
				(type default)
			)
			(layer "B.Fab")
		)
		(fp_line
			(start -0.120396 0.3048)
			(end -0.120396 0.2794)
			(stroke
				(width 0.1)
				(type default)
			)
			(layer "B.Fab")
		)
		(fp_line
			(start 0.12065 -0.305054)
			(end 0.12065 -0.2794)
			(stroke
				(width 0.1)
				(type default)
			)
			(layer "B.Fab")
		)
		(fp_line
			(start 0.12065 -0.2794)
			(end -0.12065 -0.2794)
			(stroke
				(width 0.1)
				(type default)
			)
			(layer "B.Fab")
		)
		(fp_line
			(start 0.12065 0.2794)
			(end 0.12065 0.3048)
			(stroke
				(width 0.1)
				(type default)
			)
			(layer "B.Fab")
		)
		(fp_line
			(start 0.12065 0.3048)
			(end 0.67945 0.3048)
			(stroke
				(width 0.1)
				(type default)
			)
			(layer "B.Fab")
		)
		(fp_line
			(start 0.67945 -0.305054)
			(end 0.12065 -0.305054)
			(stroke
				(width 0.1)
				(type default)
			)
			(layer "B.Fab")
		)
		(fp_line
			(start 0.67945 0.3048)
			(end 0.67945 -0.305054)
			(stroke
				(width 0.1)
				(type default)
			)
			(layer "B.Fab")
		)
		(pad "1" smd circle
			(at 0.40005 0 180)
			(size 0 0)
			(layers "B.Cu" "B.Mask" "B.Paste")
			(net "P3V3_AUX")
		)
		(pad "2" smd circle
			(at -0.40005 0 180)
			(size 0 0)
			(layers "B.Cu" "B.Mask" "B.Paste")
			(net "SMB_P52V_VPDB_SCL")
		)
	)
	(footprint ""
		(layer "B.Cu")
		(at 176.779174 -78.867)
		(property "Reference" "R193"
			(at 0 0 0)
			(layer "B.SilkS")
			(hide yes)
			(effects
				(font
					(size 1.27 1.27)
				)
				(justify mirror)
			)
		)
		(property "Value" ""
			(at 0 0 0)
			(layer "B.Fab")
			(effects
				(font
					(size 1.27 1.27)
				)
				(justify mirror)
			)
		)
		(duplicate_pad_numbers_are_jumpers no)
		(fp_line
			(start -0.7874 -0.4064)
			(end -0.7874 0.4064)
			(stroke
				(width 0.1524)
				(type default)
			)
			(layer "B.SilkS")
		)
		(fp_line
			(start -0.7874 0.4064)
			(end 0.7874 0.4064)
			(stroke
				(width 0.1524)
				(type default)
			)
			(layer "B.SilkS")
		)
		(fp_line
			(start 0.7874 -0.4064)
			(end -0.7874 -0.4064)
			(stroke
				(width 0.1524)
				(type default)
			)
			(layer "B.SilkS")
		)
		(fp_line
			(start 0.7874 0.4064)
			(end 0.7874 -0.4064)
			(stroke
				(width 0.1524)
				(type default)
			)
			(layer "B.SilkS")
		)
		(fp_line
			(start -0.67945 -0.3048)
			(end -0.67945 0.3048)
			(stroke
				(width 0.1)
				(type default)
			)
			(layer "B.Fab")
		)
		(fp_line
			(start -0.67945 0.3048)
			(end -0.120396 0.3048)
			(stroke
				(width 0.1)
				(type default)
			)
			(layer "B.Fab")
		)
		(fp_line
			(start -0.12065 -0.3048)
			(end -0.67945 -0.3048)
			(stroke
				(width 0.1)
				(type default)
			)
			(layer "B.Fab")
		)
		(fp_line
			(start -0.12065 -0.2794)
			(end -0.12065 -0.3048)
			(stroke
				(width 0.1)
				(type default)
			)
			(layer "B.Fab")
		)
		(fp_line
			(start -0.120396 0.2794)
			(end 0.12065 0.2794)
			(stroke
				(width 0.1)
				(type default)
			)
			(layer "B.Fab")
		)
		(fp_line
			(start -0.120396 0.3048)
			(end -0.120396 0.2794)
			(stroke
				(width 0.1)
				(type default)
			)
			(layer "B.Fab")
		)
		(fp_line
			(start 0.12065 -0.305054)
			(end 0.12065 -0.2794)
			(stroke
				(width 0.1)
				(type default)
			)
			(layer "B.Fab")
		)
		(fp_line
			(start 0.12065 -0.2794)
			(end -0.12065 -0.2794)
			(stroke
				(width 0.1)
				(type default)
			)
			(layer "B.Fab")
		)
		(fp_line
			(start 0.12065 0.2794)
			(end 0.12065 0.3048)
			(stroke
				(width 0.1)
				(type default)
			)
			(layer "B.Fab")
		)
		(fp_line
			(start 0.12065 0.3048)
			(end 0.67945 0.3048)
			(stroke
				(width 0.1)
				(type default)
			)
			(layer "B.Fab")
		)
		(fp_line
			(start 0.67945 -0.305054)
			(end 0.12065 -0.305054)
			(stroke
				(width 0.1)
				(type default)
			)
			(layer "B.Fab")
		)
		(fp_line
			(start 0.67945 0.3048)
			(end 0.67945 -0.305054)
			(stroke
				(width 0.1)
				(type default)
			)
			(layer "B.Fab")
		)
		(pad "1" smd circle
			(at 0.40005 0 180)
			(size 0 0)
			(layers "B.Cu" "B.Mask" "B.Paste")
			(net "P3V3_AUX")
		)
		(pad "2" smd circle
			(at -0.40005 0 180)
			(size 0 0)
			(layers "B.Cu" "B.Mask" "B.Paste")
			(net "P12V_BRICK2_ALERT_N")
		)
	)
	(footprint ""
		(layer "B.Cu")
		(at 279.908 -42.799)
		(property "Reference" "PR93"
			(at 0 0 0)
			(layer "B.SilkS")
			(hide yes)
			(effects
				(font
					(size 1.27 1.27)
				)
				(justify mirror)
			)
		)
		(property "Value" ""
			(at 0 0 0)
			(layer "B.Fab")
			(effects
				(font
					(size 1.27 1.27)
				)
				(justify mirror)
			)
		)
		(duplicate_pad_numbers_are_jumpers no)
		(fp_line
			(start -0.7874 -0.4064)
			(end -0.7874 0.4064)
			(stroke
				(width 0.1524)
				(type default)
			)
			(layer "B.SilkS")
		)
		(fp_line
			(start -0.7874 0.4064)
			(end 0.7874 0.4064)
			(stroke
				(width 0.1524)
				(type default)
			)
			(layer "B.SilkS")
		)
		(fp_line
			(start 0.7874 -0.4064)
			(end -0.7874 -0.4064)
			(stroke
				(width 0.1524)
				(type default)
			)
			(layer "B.SilkS")
		)
		(fp_line
			(start 0.7874 0.4064)
			(end 0.7874 -0.4064)
			(stroke
				(width 0.1524)
				(type default)
			)
			(layer "B.SilkS")
		)
		(fp_line
			(start -0.67945 -0.3048)
			(end -0.67945 0.3048)
			(stroke
				(width 0.1)
				(type default)
			)
			(layer "B.Fab")
		)
		(fp_line
			(start -0.67945 0.3048)
			(end -0.120396 0.3048)
			(stroke
				(width 0.1)
				(type default)
			)
			(layer "B.Fab")
		)
		(fp_line
			(start -0.12065 -0.3048)
			(end -0.67945 -0.3048)
			(stroke
				(width 0.1)
				(type default)
			)
			(layer "B.Fab")
		)
		(fp_line
			(start -0.12065 -0.2794)
			(end -0.12065 -0.3048)
			(stroke
				(width 0.1)
				(type default)
			)
			(layer "B.Fab")
		)
		(fp_line
			(start -0.120396 0.2794)
			(end 0.12065 0.2794)
			(stroke
				(width 0.1)
				(type default)
			)
			(layer "B.Fab")
		)
		(fp_line
			(start -0.120396 0.3048)
			(end -0.120396 0.2794)
			(stroke
				(width 0.1)
				(type default)
			)
			(layer "B.Fab")
		)
		(fp_line
			(start 0.12065 -0.305054)
			(end 0.12065 -0.2794)
			(stroke
				(width 0.1)
				(type default)
			)
			(layer "B.Fab")
		)
		(fp_line
			(start 0.12065 -0.2794)
			(end -0.12065 -0.2794)
			(stroke
				(width 0.1)
				(type default)
			)
			(layer "B.Fab")
		)
		(fp_line
			(start 0.12065 0.2794)
			(end 0.12065 0.3048)
			(stroke
				(width 0.1)
				(type default)
			)
			(layer "B.Fab")
		)
		(fp_line
			(start 0.12065 0.3048)
			(end 0.67945 0.3048)
			(stroke
				(width 0.1)
				(type default)
			)
			(layer "B.Fab")
		)
		(fp_line
			(start 0.67945 -0.305054)
			(end 0.12065 -0.305054)
			(stroke
				(width 0.1)
				(type default)
			)
			(layer "B.Fab")
		)
		(fp_line
			(start 0.67945 0.3048)
			(end 0.67945 -0.305054)
			(stroke
				(width 0.1)
				(type default)
			)
			(layer "B.Fab")
		)
		(pad "1" smd circle
			(at 0.40005 0 180)
			(size 0 0)
			(layers "B.Cu" "B.Mask" "B.Paste")
			(net "P52V_HS1_ESTART_R")
		)
		(pad "2" smd circle
			(at -0.40005 0 180)
			(size 0 0)
			(layers "B.Cu" "B.Mask" "B.Paste")
			(net "P52V_HS1_ESTART")
		)
	)
)
